(kicad_pcb
	(version 20241229)
	(generator "pcbnew")
	(generator_version "9.0")
	(general
		(thickness 1.62)
		(legacy_teardrops no)
	)
	(paper "A3")
	(title_block
		(title "COM Express 7 Baseboard")
		(date "2025-02-04")
		(rev "1.1.2")
		(company "Antmicro Ltd")
		(comment 1 "www.antmicro.com")
		(comment 9 "footprints 224-227 of 802")
	)
	(layers
		(0 "F.Cu" signal)
		(4 "In1.Cu" signal)
		(6 "In2.Cu" signal)
		(8 "In3.Cu" signal)
		(10 "In4.Cu" signal)
		(12 "In5.Cu" signal)
		(14 "In6.Cu" signal)
		(2 "B.Cu" signal)
		(9 "F.Adhes" user "F.Adhesive")
		(11 "B.Adhes" user "B.Adhesive")
		(13 "F.Paste" user)
		(15 "B.Paste" user)
		(5 "F.SilkS" user "F.Silkscreen")
		(7 "B.SilkS" user "B.Silkscreen")
		(1 "F.Mask" user)
		(3 "B.Mask" user)
		(17 "Dwgs.User" user "User.Drawings")
		(19 "Cmts.User" user "User.Comments")
		(21 "Eco1.User" user "User.Eco1")
		(23 "Eco2.User" user "User.Eco2")
		(25 "Edge.Cuts" user)
		(27 "Margin" user)
		(31 "F.CrtYd" user "F.Courtyard")
		(29 "B.CrtYd" user "B.Courtyard")
		(35 "F.Fab" user)
		(33 "B.Fab" user)
	)
	(footprint "antmicro-footprints:R_0402_1005Metric"
		(layer "F.Cu")
		(at 143 135.88 180)
		(descr "Resistor SMD 0402")
		(tags "resistor SMD 0402")
		(property "Reference" "R246"
			(at 0.75 -0.43 0)
			(layer "F.SilkS")
			(effects
				(font
					(size 0.7 0.7)
					(thickness 0.15)
				)
				(justify right bottom)
			)
		)
		(property "Value" "R_100k_0402"
			(at -1.011843 1.772047 0)
			(layer "F.Fab")
			(effects
				(font
					(size 0.7 0.7)
					(thickness 0.15)
				)
				(justify right bottom)
			)
		)
		(property "Datasheet" "https://www.bourns.com/docs/product-datasheets/cr.pdf"
			(at 0 0 180)
			(layer "F.Fab")
			(hide yes)
			(effects
				(font
					(size 1.27 1.27)
					(thickness 0.15)
				)
			)
		)
		(property "Author" "Antmicro"
			(at 286 271.76 0)
			(layer "F.Fab")
			(hide yes)
			(effects
				(font
					(size 1 1)
					(thickness 0.15)
				)
			)
		)
		(property "License" "Apache-2.0"
			(at 286 271.76 0)
			(layer "F.Fab")
			(hide yes)
			(effects
				(font
					(size 1 1)
					(thickness 0.15)
				)
			)
		)
		(property "MPN" "CR0402-FX-1003GLF"
			(at 286 271.76 0)
			(layer "F.Fab")
			(hide yes)
			(effects
				(font
					(size 1 1)
					(thickness 0.15)
				)
			)
		)
		(property "Manufacturer" "Bourns"
			(at 286 271.76 0)
			(layer "F.Fab")
			(hide yes)
			(effects
				(font
					(size 1 1)
					(thickness 0.15)
				)
			)
		)
		(property "Public" "False"
			(at 286 271.76 0)
			(layer "F.Fab")
			(hide yes)
			(effects
				(font
					(size 1 1)
					(thickness 0.15)
				)
			)
		)
		(property "Tolerance" "1%"
			(at 286 271.76 0)
			(layer "F.Fab")
			(hide yes)
			(effects
				(font
					(size 1 1)
					(thickness 0.15)
				)
			)
		)
		(property "Val" "100k"
			(at 286 271.76 0)
			(layer "F.Fab")
			(hide yes)
			(effects
				(font
					(size 1 1)
					(thickness 0.15)
				)
			)
		)
		(sheetname "KR to SFI #1")
		(sheetfile "kr_sfi.kicad_sch")
		(attr smd)
		(fp_rect
			(start -0.925 -0.47)
			(end 0.925 0.47)
			(stroke
				(width 0.05)
				(type default)
			)
			(fill no)
			(layer "F.CrtYd")
		)
		(fp_rect
			(start -0.5 -0.25)
			(end 0.5 0.25)
			(stroke
				(width 0.15)
				(type solid)
			)
			(fill no)
			(layer "F.Fab")
		)
		(pad "1" smd roundrect
			(at -0.48 0 180)
			(size 0.59 0.64)
			(layers "F.Cu" "F.Mask" "F.Paste")
			(roundrect_rratio 0.25)
			(net 2 "+3V3")
			(pintype "passive")
			(teardrops
				(best_length_ratio 0.2)
				(max_length 1)
				(best_width_ratio 0.9)
				(max_width 2)
				(curved_edges yes)
				(filter_ratio 0.9)
				(enabled yes)
				(allow_two_segments yes)
				(prefer_zone_connections yes)
			)
		)
		(pad "2" smd roundrect
			(at 0.48 0 180)
			(size 0.59 0.64)
			(layers "F.Cu" "F.Mask" "F.Paste")
			(roundrect_rratio 0.25)
			(net 647 "Net-(Y2-EN)")
			(pintype "passive")
			(teardrops
				(best_length_ratio 0.2)
				(max_length 1)
				(best_width_ratio 0.9)
				(max_width 2)
				(curved_edges yes)
				(filter_ratio 0.9)
				(enabled yes)
				(allow_two_segments yes)
				(prefer_zone_connections yes)
			)
		)
	)
	(footprint "antmicro-footprints:LED_0603_1608Metric_G"
		(layer "F.Cu")
		(at 114.95 69.86 90)
		(descr "LED SMD 0603 Green")
		(tags "LED SMD 0603 Green")
		(property "Reference" "D16"
			(at -3.4 0.45 90)
			(layer "F.SilkS")
			(effects
				(font
					(size 0.7 0.7)
					(thickness 0.15)
				)
				(justify left bottom)
			)
		)
		(property "Value" "LED_G_0603_LTST-C190GKT"
			(at -0.001 1.599 90)
			(layer "F.Fab")
			(effects
				(font
					(size 0.7 0.7)
					(thickness 0.15)
				)
				(justify left bottom)
			)
		)
		(property "Datasheet" "https://media.digikey.com/pdf/Data%20Sheets/Lite-On%20PDFs/LTST-C190GKT.pdf"
			(at 0 0 90)
			(layer "F.Fab")
			(hide yes)
			(effects
				(font
					(size 1.27 1.27)
					(thickness 0.15)
				)
			)
		)
		(property "Author" "Antmicro"
			(at 184.81 -45.09 0)
			(layer "F.Fab")
			(hide yes)
			(effects
				(font
					(size 1 1)
					(thickness 0.15)
				)
			)
		)
		(property "Color" "Green"
			(at 184.81 -45.09 0)
			(layer "F.Fab")
			(hide yes)
			(effects
				(font
					(size 1 1)
					(thickness 0.15)
				)
			)
		)
		(property "License" "Apache-2.0"
			(at 184.81 -45.09 0)
			(layer "F.Fab")
			(hide yes)
			(effects
				(font
					(size 1 1)
					(thickness 0.15)
				)
			)
		)
		(property "MPN" "LTST-C190GKT"
			(at 184.81 -45.09 0)
			(layer "F.Fab")
			(hide yes)
			(effects
				(font
					(size 1 1)
					(thickness 0.15)
				)
			)
		)
		(property "Manufacturer" "Lite-On"
			(at 184.81 -45.09 0)
			(layer "F.Fab")
			(hide yes)
			(effects
				(font
					(size 1 1)
					(thickness 0.15)
				)
			)
		)
		(property "Public" "False"
			(at 184.81 -45.09 0)
			(layer "F.Fab")
			(hide yes)
			(effects
				(font
					(size 1 1)
					(thickness 0.15)
				)
			)
		)
		(sheetname "M.2 key E")
		(sheetfile "m2keye.kicad_sch")
		(attr smd)
		(fp_line
			(start 0.22 -0.35)
			(end -0.22 -0.35)
			(stroke
				(width 0.15)
				(type solid)
			)
			(layer "F.SilkS")
		)
		(fp_line
			(start -1.18 -0.319)
			(end -1.18 0.321)
			(stroke
				(width 0.15)
				(type solid)
			)
			(layer "F.SilkS")
		)
		(fp_line
			(start 0.105328 0.001008)
			(end 0.24 0.001)
			(stroke
				(width 0.1)
				(type solid)
			)
			(layer "F.SilkS")
		)
		(fp_line
			(start -0.094672 0.001008)
			(end 0.105328 -0.198992)
			(stroke
				(width 0.1)
				(type solid)
			)
			(layer "F.SilkS")
		)
		(fp_line
			(start -0.094672 0.001008)
			(end -0.24 0.001008)
			(stroke
				(width 0.1)
				(type solid)
			)
			(layer "F.SilkS")
		)
		(fp_line
			(start 0.105328 0.201008)
			(end 0.105328 -0.198992)
			(stroke
				(width 0.1)
				(type solid)
			)
			(layer "F.SilkS")
		)
		(fp_line
			(start 0.105328 0.201008)
			(end -0.094672 0.001008)
			(stroke
				(width 0.1)
				(type solid)
			)
			(layer "F.SilkS")
		)
		(fp_line
			(start -0.094672 0.201008)
			(end -0.094672 -0.198992)
			(stroke
				(width 0.1)
				(type solid)
			)
			(layer "F.SilkS")
		)
		(fp_line
			(start 0.22 0.35)
			(end -0.22 0.35)
			(stroke
				(width 0.15)
				(type solid)
			)
			(layer "F.SilkS")
		)
		(fp_rect
			(start 1.25 0.65)
			(end -1.25 -0.65)
			(stroke
				(width 0.05)
				(type solid)
			)
			(fill no)
			(layer "F.CrtYd")
		)
		(fp_line
			(start 0.201 -0.202)
			(end -0.101 0)
			(stroke
				(width 0.15)
				(type solid)
			)
			(layer "F.Fab")
		)
		(fp_line
			(start -0.199 -0.202)
			(end -0.199 0.1)
			(stroke
				(width 0.15)
				(type solid)
			)
			(layer "F.Fab")
		)
		(fp_line
			(start 0.599 0)
			(end 0.201 0)
			(stroke
				(width 0.15)
				(type solid)
			)
			(layer "F.Fab")
		)
		(fp_line
			(start 0.201 0)
			(end 0.201 -0.202)
			(stroke
				(width 0.15)
				(type solid)
			)
			(layer "F.Fab")
		)
		(fp_line
			(start -0.101 0)
			(end 0.201 0.2)
			(stroke
				(width 0.15)
				(type solid)
			)
			(layer "F.Fab")
		)
		(fp_line
			(start -0.199 0)
			(end -0.597 0)
			(stroke
				(width 0.15)
				(type solid)
			)
			(layer "F.Fab")
		)
		(fp_line
			(start 0.201 0.2)
			(end 0.201 0)
			(stroke
				(width 0.15)
				(type solid)
			)
			(layer "F.Fab")
		)
		(fp_line
			(start -0.199 0.2)
			(end -0.199 0.1)
			(stroke
				(width 0.15)
				(type solid)
			)
			(layer "F.Fab")
		)
		(fp_rect
			(start 0.848 0.4)
			(end -0.85 -0.402)
			(stroke
				(width 0.15)
				(type solid)
			)
			(fill no)
			(layer "F.Fab")
		)
		(pad "1" smd roundrect
			(at -0.7 0 270)
			(size 0.8 1)
			(layers "F.Cu" "F.Mask" "F.Paste")
			(roundrect_rratio 0.2)
			(net 6 "/M.2 key E/~{LED_2}")
			(pinfunction "C")
			(pintype "passive")
			(teardrops
				(best_length_ratio 0.2)
				(max_length 1)
				(best_width_ratio 0.9)
				(max_width 2)
				(curved_edges yes)
				(filter_ratio 0.9)
				(enabled yes)
				(allow_two_segments yes)
				(prefer_zone_connections yes)
			)
		)
		(pad "2" smd roundrect
			(at 0.7 0 270)
			(size 0.8 1)
			(layers "F.Cu" "F.Mask" "F.Paste")
			(roundrect_rratio 0.2)
			(net 938 "Net-(D16-A)")
			(pinfunction "A")
			(pintype "passive")
			(teardrops
				(best_length_ratio 0.2)
				(max_length 1)
				(best_width_ratio 0.9)
				(max_width 2)
				(curved_edges yes)
				(filter_ratio 0.9)
				(enabled yes)
				(allow_two_segments yes)
				(prefer_zone_connections yes)
			)
		)
	)
	(footprint "antmicro-footprints:R_0402_1005Metric"
		(layer "F.Cu")
		(at 124.84 132.88)
		(descr "Resistor SMD 0402")
		(tags "resistor SMD 0402")
		(property "Reference" "R302"
			(at -3.69 0.43 0)
			(layer "F.SilkS")
			(effects
				(font
					(size 0.7 0.7)
					(thickness 0.15)
				)
				(justify left bottom)
			)
		)
		(property "Value" "R_10k_0402"
			(at -1.011843 1.772047 0)
			(layer "F.Fab")
			(effects
				(font
					(size 0.7 0.7)
					(thickness 0.15)
				)
				(justify left bottom)
			)
		)
		(property "Datasheet" "https://www.bourns.com/docs/product-datasheets/cr.pdf"
			(at 0 0 0)
			(layer "F.Fab")
			(hide yes)
			(effects
				(font
					(size 1.27 1.27)
					(thickness 0.15)
				)
			)
		)
		(property "Author" "Antmicro"
			(at 0 0 0)
			(layer "F.Fab")
			(hide yes)
			(effects
				(font
					(size 1 1)
					(thickness 0.15)
				)
			)
		)
		(property "License" "Apache-2.0"
			(at 0 0 0)
			(layer "F.Fab")
			(hide yes)
			(effects
				(font
					(size 1 1)
					(thickness 0.15)
				)
			)
		)
		(property "MPN" "CR0402-FX-1002GLF"
			(at 0 0 0)
			(layer "F.Fab")
			(hide yes)
			(effects
				(font
					(size 1 1)
					(thickness 0.15)
				)
			)
		)
		(property "Manufacturer" "Bourns"
			(at 0 0 0)
			(layer "F.Fab")
			(hide yes)
			(effects
				(font
					(size 1 1)
					(thickness 0.15)
				)
			)
		)
		(property "Public" "False"
			(at 0 0 0)
			(layer "F.Fab")
			(hide yes)
			(effects
				(font
					(size 1 1)
					(thickness 0.15)
				)
			)
		)
		(property "Tolerance" "1%"
			(at 0 0 0)
			(layer "F.Fab")
			(hide yes)
			(effects
				(font
					(size 1 1)
					(thickness 0.15)
				)
			)
		)
		(property "Val" "10k"
			(at 0 0 0)
			(layer "F.Fab")
			(hide yes)
			(effects
				(font
					(size 1 1)
					(thickness 0.15)
				)
			)
		)
		(sheetname "KR to SFI #2")
		(sheetfile "kr_sfi.kicad_sch")
		(attr smd)
		(fp_rect
			(start -0.925 -0.47)
			(end 0.925 0.47)
			(stroke
				(width 0.05)
				(type default)
			)
			(fill no)
			(layer "F.CrtYd")
		)
		(fp_rect
			(start -0.5 -0.25)
			(end 0.5 0.25)
			(stroke
				(width 0.15)
				(type solid)
			)
			(fill no)
			(layer "F.Fab")
		)
		(pad "1" smd roundrect
			(at -0.48 0)
			(size 0.59 0.64)
			(layers "F.Cu" "F.Mask" "F.Paste")
			(roundrect_rratio 0.25)
			(net 1 "GND")
			(pintype "passive")
			(teardrops
				(best_length_ratio 0.2)
				(max_length 1)
				(best_width_ratio 0.9)
				(max_width 2)
				(curved_edges yes)
				(filter_ratio 0.9)
				(enabled yes)
				(allow_two_segments yes)
				(prefer_zone_connections yes)
			)
		)
		(pad "2" smd roundrect
			(at 0.48 0)
			(size 0.59 0.64)
			(layers "F.Cu" "F.Mask" "F.Paste")
			(roundrect_rratio 0.25)
			(net 682 "Net-(U45C-PRTAD4)")
			(pintype "passive")
			(teardrops
				(best_length_ratio 0.2)
				(max_length 1)
				(best_width_ratio 0.9)
				(max_width 2)
				(curved_edges yes)
				(filter_ratio 0.9)
				(enabled yes)
				(allow_two_segments yes)
				(prefer_zone_connections yes)
			)
		)
	)
	(footprint "antmicro-footprints:SOT-23-3"
		(layer "F.Cu")
		(at 289.4 99.41 90)
		(property "Reference" "Q3"
			(at -0.55 -3.15 180)
			(layer "F.SilkS")
			(effects
				(font
					(size 0.7 0.7)
					(thickness 0.15)
				)
				(justify left bottom)
			)
		)
		(property "Value" "BSS138-7-F"
			(at -1.9 2.7 90)
			(layer "F.Fab")
			(effects
				(font
					(size 0.7 0.7)
					(thickness 0.15)
				)
				(justify left bottom)
			)
		)
		(property "Datasheet" "https://www.diodes.com/assets/Datasheets/ds30144.pdf"
			(at 0 0 90)
			(layer "F.Fab")
			(hide yes)
			(effects
				(font
					(size 1.27 1.27)
					(thickness 0.15)
				)
			)
		)
		(property "Author" "Antmicro"
			(at 388.81 -189.99 0)
			(layer "F.Fab")
			(hide yes)
			(effects
				(font
					(size 1 1)
					(thickness 0.15)
				)
			)
		)
		(property "License" "Apache-2.0"
			(at 388.81 -189.99 0)
			(layer "F.Fab")
			(hide yes)
			(effects
				(font
					(size 1 1)
					(thickness 0.15)
				)
			)
		)
		(property "MPN" "BSS138-7-F"
			(at 388.81 -189.99 0)
			(layer "F.Fab")
			(hide yes)
			(effects
				(font
					(size 1 1)
					(thickness 0.15)
				)
			)
		)
		(property "Manufacturer" "Diodes Incorporated"
			(at 388.81 -189.99 0)
			(layer "F.Fab")
			(hide yes)
			(effects
				(font
					(size 1 1)
					(thickness 0.15)
				)
			)
		)
		(sheetname "Power")
		(sheetfile "power.kicad_sch")
		(attr smd)
		(fp_line
			(start 0.7 -1.5)
			(end -0.7 -1.5)
			(stroke
				(width 0.15)
				(type solid)
			)
			(layer "F.SilkS")
		)
		(fp_line
			(start -0.85 -1.35)
			(end -0.7 -1.5)
			(stroke
				(width 0.15)
				(type solid)
			)
			(layer "F.SilkS")
		)
		(fp_line
			(start -1.45 -1.35)
			(end -0.85 -1.35)
			(stroke
				(width 0.15)
				(type solid)
			)
			(layer "F.SilkS")
		)
		(fp_line
			(start 0.7 -0.4)
			(end 0.7 -1.5)
			(stroke
				(width 0.15)
				(type solid)
			)
			(layer "F.SilkS")
		)
		(fp_line
			(start 0.7 0.4)
			(end 0.7 1.5)
			(stroke
				(width 0.15)
				(type solid)
			)
			(layer "F.SilkS")
		)
		(fp_line
			(start 0.7 1.5)
			(end -0.7 1.5)
			(stroke
				(width 0.15)
				(type solid)
			)
			(layer "F.SilkS")
		)
		(fp_line
			(start -0.7 1.5)
			(end -0.7 1.35)
			(stroke
				(width 0.15)
				(type solid)
			)
			(layer "F.SilkS")
		)
		(fp_line
			(start 0.825 -1.6)
			(end 0.825 -0.45)
			(stroke
				(width 0.05)
				(type solid)
			)
			(layer "F.CrtYd")
		)
		(fp_line
			(start -0.9 -1.6)
			(end 0.825 -1.6)
			(stroke
				(width 0.05)
				(type solid)
			)
			(layer "F.CrtYd")
		)
		(fp_line
			(start -0.9 -1.6)
			(end -0.9 -1.4)
			(stroke
				(width 0.05)
				(type solid)
			)
			(layer "F.CrtYd")
		)
		(fp_line
			(start -0.9 -1.4)
			(end -1.75 -1.4)
			(stroke
				(width 0.05)
				(type solid)
			)
			(layer "F.CrtYd")
		)
		(fp_line
			(start -0.85 -0.5)
			(end -1.75 -0.5)
			(stroke
				(width 0.05)
				(type solid)
			)
			(layer "F.CrtYd")
		)
		(fp_line
			(start -1.75 -0.5)
			(end -1.75 -1.4)
			(stroke
				(width 0.05)
				(type solid)
			)
			(layer "F.CrtYd")
		)
		(fp_line
			(start 1.75 -0.45)
			(end 1.75 0.45)
			(stroke
				(width 0.05)
				(type solid)
			)
			(layer "F.CrtYd")
		)
		(fp_line
			(start 0.825 -0.45)
			(end 1.75 -0.45)
			(stroke
				(width 0.05)
				(type solid)
			)
			(layer "F.CrtYd")
		)
		(fp_line
			(start 1.75 0.45)
			(end 0.85 0.45)
			(stroke
				(width 0.05)
				(type solid)
			)
			(layer "F.CrtYd")
		)
		(fp_line
			(start 0.85 0.45)
			(end 0.85 1.65)
			(stroke
				(width 0.05)
				(type solid)
			)
			(layer "F.CrtYd")
		)
		(fp_line
			(start -0.85 0.5)
			(end -0.85 -0.5)
			(stroke
				(width 0.05)
				(type solid)
			)
			(layer "F.CrtYd")
		)
		(fp_line
			(start -1.75 0.5)
			(end -0.85 0.5)
			(stroke
				(width 0.05)
				(type solid)
			)
			(layer "F.CrtYd")
		)
		(fp_line
			(start -0.85 1.4)
			(end -1.75 1.4)
			(stroke
				(width 0.05)
				(type solid)
			)
			(layer "F.CrtYd")
		)
		(fp_line
			(start -1.75 1.4)
			(end -1.75 0.5)
			(stroke
				(width 0.05)
				(type solid)
			)
			(layer "F.CrtYd")
		)
		(fp_line
			(start 0.85 1.65)
			(end -0.85 1.65)
			(stroke
				(width 0.05)
				(type solid)
			)
			(layer "F.CrtYd")
		)
		(fp_line
			(start -0.85 1.65)
			(end -0.85 1.4)
			(stroke
				(width 0.05)
				(type solid)
			)
			(layer "F.CrtYd")
		)
		(fp_line
			(start -0.437 -1.526)
			(end 0.688 -1.526)
			(stroke
				(width 0.15)
				(type solid)
			)
			(layer "F.Fab")
		)
		(fp_line
			(start -0.437 -1.526)
			(end -0.712 -1.325)
			(stroke
				(width 0.15)
				(type solid)
			)
			(layer "F.Fab")
		)
		(fp_line
			(start -0.712 -1.325)
			(end -0.712 1.523)
			(stroke
				(width 0.15)
				(type solid)
			)
			(layer "F.Fab")
		)
		(fp_line
			(start 0.688 1.519)
			(end 0.688 -1.52)
			(stroke
				(width 0.15)
				(type solid)
			)
			(layer "F.Fab")
		)
		(fp_line
			(start -0.712 1.519)
			(end 0.688 1.519)
			(stroke
				(width 0.15)
				(type solid)
			)
			(layer "F.Fab")
		)
		(pad "1" smd roundrect
			(at -1.1 -0.951 90)
			(size 1 0.6)
			(layers "F.Cu" "F.Mask" "F.Paste")
			(roundrect_rratio 0.15)
			(net 535 "Net-(Q3-G)")
			(pinfunction "G")
			(pintype "bidirectional")
			(teardrops
				(best_length_ratio 0.2)
				(max_length 1)
				(best_width_ratio 0.9)
				(max_width 2)
				(curved_edges yes)
				(filter_ratio 0.9)
				(enabled yes)
				(allow_two_segments yes)
				(prefer_zone_connections yes)
			)
		)
		(pad "2" smd roundrect
			(at -1.1 0.949 90)
			(size 1 0.6)
			(layers "F.Cu" "F.Mask" "F.Paste")
			(roundrect_rratio 0.15)
			(net 1 "GND")
			(pinfunction "S")
			(pintype "bidirectional")
			(teardrops
				(best_length_ratio 0.2)
				(max_length 1)
				(best_width_ratio 0.9)
				(max_width 2)
				(curved_edges yes)
				(filter_ratio 0.9)
				(enabled yes)
				(allow_two_segments yes)
				(prefer_zone_connections yes)
			)
		)
		(pad "3" smd roundrect
			(at 1.1 -0.0005 90)
			(size 1 0.6)
			(layers "F.Cu" "F.Mask" "F.Paste")
			(roundrect_rratio 0.15)
			(net 536 "Net-(Q3-D)")
			(pinfunction "D")
			(pintype "bidirectional")
			(teardrops
				(best_length_ratio 0.2)
				(max_length 1)
				(best_width_ratio 0.9)
				(max_width 2)
				(curved_edges yes)
				(filter_ratio 0.9)
				(enabled yes)
				(allow_two_segments yes)
				(prefer_zone_connections yes)
			)
		)
	)
)
